# BASEBOARD_FAB2 (Tioga Pass) — schematic netlist excerpt (pin names and nets, part order shuffled) for the footprints in the layout excerpt that follows; sources: Cadence DE-HDL packaged netlist, KiCad conversion of Wiwynn_Tioga_Pass_MB.brd

U1L3  ADM809  IC  pkg SMLF  page 196 : RESET_N = PWRGD_P3V3_R1 ; VCC = P3V3

T1P6  TPAD-DIFF-4P-GP  pkg DISCRET-GB3  page 256
  \1\  = L14_85OHM_6INCH_DP
  \2\  = L14_85OHM_6INCH_DN
  GND1  = GND
  GND2  = GND

(kicad_pcb
	(version 20260206)
	(generator "pcbnew")
	(generator_version "10.0")
	(general
		(thickness 1.6)
		(legacy_teardrops no)
	)
	(paper "A4")
	(title_block
		(title "Wiwynn_Tioga_Pass_MB.brd")
		(comment 1 "Tioga Pass / footprints 1900-1901 of 4770")
	)
	(layers
		(0 "F.Cu" signal "TOP")
		(4 "In1.Cu" signal "L2GND")
		(6 "In2.Cu" signal "L3")
		(8 "In3.Cu" signal "L4GND")
		(10 "In4.Cu" signal "L5")
		(12 "In5.Cu" signal "L6GND")
		(14 "In6.Cu" signal "L7VCC")
		(16 "In7.Cu" signal "L8VCC")
		(18 "In8.Cu" signal "L9GND")
		(20 "In9.Cu" signal "L10")
		(22 "In10.Cu" signal "L11GND")
		(24 "In11.Cu" signal "L12")
		(26 "In12.Cu" signal "L13GND")
		(2 "B.Cu" signal "BOTTOM")
		(9 "F.Adhes" user "F.Adhesive")
		(11 "B.Adhes" user "B.Adhesive")
		(13 "F.Paste" user "Package Geometry/Pastemask Top")
		(15 "B.Paste" user "Package Geometry/Pastemask Bottom")
		(5 "F.SilkS" user "Ref Des/Silkscreen Top")
		(7 "B.SilkS" user "Ref Des/Silkscreen Bottom")
		(1 "F.Mask" user "Board Geometry/Soldermask Top")
		(3 "B.Mask" user "Board Geometry/Soldermask Bottom")
		(17 "Dwgs.User" user "User.Drawings")
		(19 "Cmts.User" user "User.Comments")
		(21 "Eco1.User" user "User.Eco1")
		(23 "Eco2.User" user "User.Eco2")
		(25 "Edge.Cuts" user "Board Geometry/Outline")
		(27 "Margin" user)
		(31 "F.CrtYd" user "Package Geometry/Place Bound Top")
		(29 "B.CrtYd" user "Package Geometry/Place Bound Bottom")
		(35 "F.Fab" user "Ref Des/Assembly Top")
		(33 "B.Fab" user "Ref Des/Assembly Bottom")
	)
	(footprint ""
		(layer "F.Cu")
		(at 476.2246 -145.8849 -90)
		(property "Reference" "U1L3"
			(at 4.98094 2.76733 90)
			(unlocked yes)
			(layer "F.SilkS")
			(effects
				(font
					(size 0.7874 0.5842)
					(thickness 0.1524)
				)
				(justify left)
			)
		)
		(property "Value" ""
			(at 0 0 270)
			(layer "F.Fab")
			(effects
				(font
					(size 1.27 1.27)
				)
			)
		)
		(duplicate_pad_numbers_are_jumpers no)
		(fp_line
			(start 0.9525 2.4765)
			(end 1.778 2.4765)
			(stroke
				(width 0.1524)
				(type default)
			)
			(layer "F.SilkS")
		)
		(fp_line
			(start 1.778 2.4765)
			(end 1.778 1.5875)
			(stroke
				(width 0.1524)
				(type default)
			)
			(layer "F.SilkS")
		)
		(fp_line
			(start 0.381 0.635)
			(end 0.381 1.27)
			(stroke
				(width 0.1524)
				(type default)
			)
			(layer "F.SilkS")
		)
		(fp_line
			(start 0.9525 -0.5715)
			(end 1.778 -0.5715)
			(stroke
				(width 0.1524)
				(type default)
			)
			(layer "F.SilkS")
		)
		(fp_line
			(start 1.778 -0.5715)
			(end 1.778 0.3175)
			(stroke
				(width 0.1524)
				(type default)
			)
			(layer "F.SilkS")
		)
		(fp_circle
			(center -0.9525 -0.9271)
			(end -0.9525 -1.0541)
			(stroke
				(width 0.254)
				(type default)
			)
			(fill no)
			(layer "F.SilkS")
		)
		(fp_poly
			(pts
				(xy 1.778 2.4765) (xy 0.381 2.4765) (xy 0.381 -0.5715) (xy 1.778 -0.5715)
			)
			(stroke
				(width 0)
				(type default)
			)
			(fill no)
			(layer "F.CrtYd")
		)
		(fp_line
			(start 0.381 2.4765)
			(end 1.778 2.4765)
			(stroke
				(width 0.1)
				(type default)
			)
			(layer "F.Fab")
		)
		(fp_line
			(start 1.778 2.4765)
			(end 1.778 -0.5715)
			(stroke
				(width 0.1)
				(type default)
			)
			(layer "F.Fab")
		)
		(fp_line
			(start 0.381 -0.5715)
			(end 0.381 2.4765)
			(stroke
				(width 0.1)
				(type default)
			)
			(layer "F.Fab")
		)
		(fp_line
			(start 1.778 -0.5715)
			(end 0.381 -0.5715)
			(stroke
				(width 0.1)
				(type default)
			)
			(layer "F.Fab")
		)
		(fp_circle
			(center -0.9525 -0.9271)
			(end -0.9525 -1.0541)
			(stroke
				(width 0.254)
				(type default)
			)
			(fill no)
			(layer "F.Fab")
		)
		(pad "1" smd rect
			(at 0 0 270)
			(size 1.143 0.508)
			(layers "F.Cu" "F.Mask" "F.Paste")
			(net "GND")
		)
		(pad "2" smd rect
			(at 0 1.905 270)
			(size 1.143 0.508)
			(layers "F.Cu" "F.Mask" "F.Paste")
			(net "PWRGD_P3V3_R1")
		)
		(pad "3" smd rect
			(at 2.159 0.9525 270)
			(size 1.143 0.508)
			(layers "F.Cu" "F.Mask" "F.Paste")
			(net "P3V3")
		)
	)
	(footprint ""
		(layer "F.Cu")
		(at 227.071936 11.952478 -90)
		(property "Reference" "T1P6"
			(at 0 0 270)
			(layer "F.SilkS")
			(hide yes)
			(effects
				(font
					(size 1.27 1.27)
				)
			)
		)
		(property "Value" "*"
			(at -3.302 1.12395 270)
			(unlocked yes)
			(layer "F.Fab")
			(hide yes)
			(effects
				(font
					(size 0.889 0.889)
					(thickness 0.1524)
				)
			)
		)
		(property "Device Type" "TPAD-DIFF-4P-GP_DISCRET-GB3-TPA"
			(at -3.302 -0.40005 270)
			(unlocked yes)
			(layer "F.Fab")
			(hide yes)
			(effects
				(font
					(size 0.889 0.889)
					(thickness 0.1524)
				)
			)
		)
		(duplicate_pad_numbers_are_jumpers no)
		(fp_line
			(start -2.286 2.286)
			(end 2.286 2.286)
			(stroke
				(width 0.1524)
				(type default)
			)
			(layer "F.SilkS")
		)
		(fp_line
			(start 2.286 2.286)
			(end 2.286 -2.286)
			(stroke
				(width 0.1524)
				(type default)
			)
			(layer "F.SilkS")
		)
		(fp_line
			(start -2.286 -2.286)
			(end -2.286 2.286)
			(stroke
				(width 0.1524)
				(type default)
			)
			(layer "F.SilkS")
		)
		(fp_line
			(start 2.286 -2.286)
			(end -2.286 -2.286)
			(stroke
				(width 0.1524)
				(type default)
			)
			(layer "F.SilkS")
		)
		(fp_line
			(start -2.413 -2.413)
			(end -2.413 -1.143)
			(stroke
				(width 0.4064)
				(type default)
			)
			(layer "F.SilkS")
		)
		(fp_line
			(start -1.143 -2.413)
			(end -2.413 -2.413)
			(stroke
				(width 0.4064)
				(type default)
			)
			(layer "F.SilkS")
		)
		(fp_rect
			(start -2.54 2.54)
			(end 2.54 -2.54)
			(stroke
				(width 0)
				(type default)
			)
			(fill no)
			(layer "F.CrtYd")
		)
		(fp_rect
			(start -2.54 2.54)
			(end 2.54 -2.54)
			(stroke
				(width 0)
				(type default)
			)
			(fill no)
			(layer "F.Fab")
		)
		(pad "1" thru_hole circle
			(at -1.27 -1.27 270)
			(size 1.524 1.524)
			(drill 0.9144)
			(layers "*.Cu" "*.Mask")
			(remove_unused_layers no)
			(net "L14_85OHM_6INCH_DP")
			(clearance -0.0508)
			(thermal_gap 0.127)
			(padstack
				(mode front_inner_back)
				(layer "Inner"
					(shape circle)
					(size 1.1684 1.1684)
					(clearance 0.127)
				)
				(layer "B.Cu"
					(shape circle)
					(size 1.524 1.524)
					(clearance -0.0508)
				)
			)
		)
		(pad "2" thru_hole circle
			(at 1.27 -1.27 270)
			(size 1.524 1.524)
			(drill 0.9144)
			(layers "*.Cu" "*.Mask")
			(remove_unused_layers no)
			(net "L14_85OHM_6INCH_DN")
			(clearance -0.0508)
			(thermal_gap 0.127)
			(padstack
				(mode front_inner_back)
				(layer "Inner"
					(shape circle)
					(size 1.1684 1.1684)
					(clearance 0.127)
				)
				(layer "B.Cu"
					(shape circle)
					(size 1.524 1.524)
					(clearance -0.0508)
				)
			)
		)
		(pad "GND1" thru_hole rect
			(at -1.27 1.27 270)
			(size 1.524 1.524)
			(drill 0.9144)
			(layers "*.Cu" "*.Mask")
			(remove_unused_layers no)
			(net "GND")
			(clearance -0.0508)
			(thermal_gap 0.127)
			(padstack
				(mode front_inner_back)
				(layer "Inner"
					(shape circle)
					(size 1.1684 1.1684)
					(clearance 0.127)
				)
				(layer "B.Cu"
					(shape rect)
					(size 1.524 1.524)
					(clearance -0.0508)
				)
			)
		)
		(pad "GND2" thru_hole rect
			(at 1.27 1.27 270)
			(size 1.524 1.524)
			(drill 0.9144)
			(layers "*.Cu" "*.Mask")
			(remove_unused_layers no)
			(net "GND")
			(clearance -0.0508)
			(thermal_gap 0.127)
			(padstack
				(mode front_inner_back)
				(layer "Inner"
					(shape circle)
					(size 1.1684 1.1684)
					(clearance 0.127)
				)
				(layer "B.Cu"
					(shape rect)
					(size 1.524 1.524)
					(clearance -0.0508)
				)
			)
		)
	)
)
